FILE_TYPE = MULTI_PHYS_TABLE;

PART 'DT1240E04LP7'

{========================================================================================}
:VALUE            | PART_TYPE | MATERIAL | PART_NUMBER    = STANDARD    | LIFECYCLE      | PART_NUMBER   | JEDEC_TYPE               | DESCRIPTION                         | MANUFTR | MANUF_PN         | RD_CMPLS_LVL | CMPLS_LVL | CLASS | DIP_SMD | FP_ECN | FROM_PJ     | DATA                     | EE_CHECK_LIST | STATUS | PSL | PREFERENCE | CREATOR | CREATEDAY  | ESD_CDM | ESD_HBM | ESD_MM | MSD | PIN_LENGTH_LONG_PIN | PIN_LENGTH_SHORT_PIN ;
{========================================================================================}
 'DT1240E-04LP-7' | 'SMLF'    | 'IC'     | 'BC001240Z01'(!) = ''               | ''               | 'BC001240Z01' |'U-DFN2510-10_0-5_2-5X1'| 'DIODE ARRAY DT1240E-04LP-7 (3.3V)' | 'DDS'   | 'DT1240E-04LP-7' | 'EP(V1)'     | 'EP(V1)'  | 'IC'  | ''      | ''     | 'F0CE-GARY' | 'DDS_DT1240E-04LP-7.pdf' | ''            | ''     | ''  | ''         | ''      | '20210611' | ''      | ''      | ''     | ''  | '0 MILS'            | '0 MILS'            
 'DT1240E-04LP-7' | 'SMLF'    | 'EMPTY'  | 'BC001240Z01'(!) = ''               | ''               | 'BC001240Z01' |'U-DFN2510-10_0-5_2-5X1'| 'DIODE ARRAY DT1240E-04LP-7 (3.3V)' | 'DDS'   | 'DT1240E-04LP-7' | 'EP(V1)'     | 'EP(V1)'  | 'IC'  | ''      | ''     | 'F0CE-GARY' | 'DDS_DT1240E-04LP-7.pdf' | ''            | ''     | ''  | ''         | ''      | '20210611' | ''      | ''      | ''     | ''  | '0 MILS'            | '0 MILS'            

END_PART

END.

